(kicad_pcb
	(version 20260206)
	(generator "pcbnew")
	(generator_version "10.0")
	(general
		(thickness 1.6)
		(legacy_teardrops no)
	)
	(paper "A4")
	(title_block
		(title "peb — Lightning_PEB_BRD.brd")
		(comment 1 "Lightning (Wiwynn / Facebook NVMe JBOF) / footprints 1072-1078 of 2563")
	)
	(layers
		(0 "F.Cu" signal "TOP")
		(4 "In1.Cu" signal "L2GND")
		(6 "In2.Cu" signal "L3")
		(8 "In3.Cu" signal "L4VCC")
		(10 "In4.Cu" signal "L5VCC")
		(12 "In5.Cu" signal "L6")
		(14 "In6.Cu" signal "L7GND")
		(2 "B.Cu" signal "BOTTOM")
		(9 "F.Adhes" user "F.Adhesive")
		(11 "B.Adhes" user "B.Adhesive")
		(13 "F.Paste" user "Package Geometry/Pastemask Top")
		(15 "B.Paste" user "Package Geometry/Pastemask Bottom")
		(5 "F.SilkS" user "Ref Des/Silkscreen Top")
		(7 "B.SilkS" user "Ref Des/Silkscreen Bottom")
		(1 "F.Mask" user "Board Geometry/Soldermask Top")
		(3 "B.Mask" user "Board Geometry/Soldermask Bottom")
		(17 "Dwgs.User" user "User.Drawings")
		(19 "Cmts.User" user "User.Comments")
		(21 "Eco1.User" user "User.Eco1")
		(23 "Eco2.User" user "User.Eco2")
		(25 "Edge.Cuts" user "Board Geometry/Outline")
		(27 "Margin" user)
		(31 "F.CrtYd" user "Package Geometry/Place Bound Top")
		(29 "B.CrtYd" user "Package Geometry/Place Bound Bottom")
		(35 "F.Fab" user "Ref Des/Assembly Top")
		(33 "B.Fab" user "Ref Des/Assembly Bottom")
	)
	(footprint ""
		(layer "F.Cu")
		(at 309.055008 -33.48101 180)
		(property "Reference" "R721"
			(at 0 0 180)
			(layer "F.SilkS")
			(hide yes)
			(effects
				(font
					(size 1.27 1.27)
				)
			)
		)
		(property "Value" "0R2J-2-GP"
			(at 0.064008 -3.993896 180)
			(unlocked yes)
			(layer "F.Fab")
			(hide yes)
			(effects
				(font
					(size 1.016 1.016)
					(thickness 0.1524)
				)
			)
		)
		(property "Device Type" "R402H16"
			(at 0.064008 -5.517896 180)
			(unlocked yes)
			(layer "F.Fab")
			(hide yes)
			(effects
				(font
					(size 1.016 1.016)
					(thickness 0.1524)
				)
			)
		)
		(duplicate_pad_numbers_are_jumpers no)
		(fp_line
			(start 0.508 -0.9398)
			(end -0.508 -0.9398)
			(stroke
				(width 0.1524)
				(type default)
			)
			(layer "F.SilkS")
		)
		(fp_line
			(start -0.508 -0.9398)
			(end -0.508 0.9398)
			(stroke
				(width 0.1524)
				(type default)
			)
			(layer "F.SilkS")
		)
		(fp_rect
			(start -0.508 0.9398)
			(end 0.508 -0.9398)
			(stroke
				(width 0)
				(type default)
			)
			(fill no)
			(layer "F.CrtYd")
		)
		(fp_rect
			(start -0.508 0.9398)
			(end 0.508 -0.9398)
			(stroke
				(width 0)
				(type default)
			)
			(fill no)
			(layer "F.Fab")
		)
		(pad "1" smd custom
			(at 0 -0.4445 180)
			(size 0.1397 0.1397)
			(layers "F.Cu" "F.Mask" "F.Paste")
			(net "8644_USB_DP7")
			(options
				(clearance outline)
				(anchor circle)
			)
			(primitives
				(gr_poly
					(pts
						(arc
							(start -0.1778 -0.2794)
							(mid -0.249642 -0.249642)
							(end -0.2794 -0.1778)
						)
						(arc
							(start -0.2794 0.1778)
							(mid -0.249642 0.249642)
							(end -0.1778 0.2794)
						)
						(arc
							(start 0.1778 0.2794)
							(mid 0.249642 0.249642)
							(end 0.2794 0.1778)
						)
						(arc
							(start 0.2794 -0.1778)
							(mid 0.249642 -0.249642)
							(end 0.1778 -0.2794)
						)
					)
					(width 0)
					(fill yes)
				)
			)
		)
		(pad "2" smd custom
			(at 0 0.4445 180)
			(size 0.1397 0.1397)
			(layers "F.Cu" "F.Mask" "F.Paste")
			(net "P3V3_STBY")
			(options
				(clearance outline)
				(anchor circle)
			)
			(primitives
				(gr_poly
					(pts
						(arc
							(start -0.1778 -0.2794)
							(mid -0.249642 -0.249642)
							(end -0.2794 -0.1778)
						)
						(arc
							(start -0.2794 0.1778)
							(mid -0.249642 0.249642)
							(end -0.1778 0.2794)
						)
						(arc
							(start 0.1778 0.2794)
							(mid 0.249642 0.249642)
							(end 0.2794 0.1778)
						)
						(arc
							(start 0.2794 -0.1778)
							(mid 0.249642 -0.249642)
							(end 0.1778 -0.2794)
						)
					)
					(width 0)
					(fill yes)
				)
			)
		)
	)
	(footprint ""
		(layer "F.Cu")
		(at 266.823444 -2.846832 90)
		(property "Reference" "R641"
			(at 0 0 90)
			(layer "F.SilkS")
			(hide yes)
			(effects
				(font
					(size 1.27 1.27)
				)
			)
		)
		(property "Value" "4K7R2F-GP"
			(at 0.064008 -3.993896 90)
			(unlocked yes)
			(layer "F.Fab")
			(hide yes)
			(effects
				(font
					(size 1.016 1.016)
					(thickness 0.1524)
				)
			)
		)
		(property "Device Type" "R402H16"
			(at 0.064008 -5.517896 90)
			(unlocked yes)
			(layer "F.Fab")
			(hide yes)
			(effects
				(font
					(size 1.016 1.016)
					(thickness 0.1524)
				)
			)
		)
		(duplicate_pad_numbers_are_jumpers no)
		(fp_line
			(start 0.508 -0.9398)
			(end -0.508 -0.9398)
			(stroke
				(width 0.1524)
				(type default)
			)
			(layer "F.SilkS")
		)
		(fp_line
			(start -0.508 -0.9398)
			(end -0.508 0.9398)
			(stroke
				(width 0.1524)
				(type default)
			)
			(layer "F.SilkS")
		)
		(fp_rect
			(start -0.508 0.9398)
			(end 0.508 -0.9398)
			(stroke
				(width 0)
				(type default)
			)
			(fill no)
			(layer "F.CrtYd")
		)
		(fp_rect
			(start -0.508 0.9398)
			(end 0.508 -0.9398)
			(stroke
				(width 0)
				(type default)
			)
			(fill no)
			(layer "F.Fab")
		)
		(pad "1" smd custom
			(at 0 -0.4445 90)
			(size 0.1397 0.1397)
			(layers "F.Cu" "F.Mask" "F.Paste")
			(net "SLIDE_SW_PMC_RST#")
			(options
				(clearance outline)
				(anchor circle)
			)
			(primitives
				(gr_poly
					(pts
						(arc
							(start -0.1778 -0.2794)
							(mid -0.249642 -0.249642)
							(end -0.2794 -0.1778)
						)
						(arc
							(start -0.2794 0.1778)
							(mid -0.249642 0.249642)
							(end -0.1778 0.2794)
						)
						(arc
							(start 0.1778 0.2794)
							(mid 0.249642 0.249642)
							(end 0.2794 0.1778)
						)
						(arc
							(start 0.2794 -0.1778)
							(mid 0.249642 -0.249642)
							(end 0.1778 -0.2794)
						)
					)
					(width 0)
					(fill yes)
				)
			)
		)
		(pad "2" smd custom
			(at 0 0.4445 90)
			(size 0.1397 0.1397)
			(layers "F.Cu" "F.Mask" "F.Paste")
			(net "P3V3_STBY")
			(options
				(clearance outline)
				(anchor circle)
			)
			(primitives
				(gr_poly
					(pts
						(arc
							(start -0.1778 -0.2794)
							(mid -0.249642 -0.249642)
							(end -0.2794 -0.1778)
						)
						(arc
							(start -0.2794 0.1778)
							(mid -0.249642 0.249642)
							(end -0.1778 0.2794)
						)
						(arc
							(start 0.1778 0.2794)
							(mid 0.249642 0.249642)
							(end 0.2794 0.1778)
						)
						(arc
							(start 0.2794 -0.1778)
							(mid 0.249642 -0.249642)
							(end 0.1778 -0.2794)
						)
					)
					(width 0)
					(fill yes)
				)
			)
		)
	)
	(footprint ""
		(layer "F.Cu")
		(at 5.588 -43.942)
		(property "Reference" "C330"
			(at 0 0 0)
			(layer "F.SilkS")
			(hide yes)
			(effects
				(font
					(size 1.27 1.27)
				)
			)
		)
		(property "Value" "SCD1U16V2KX-3GP"
			(at 1.1811 -2.7051 0)
			(unlocked yes)
			(layer "F.Fab")
			(hide yes)
			(effects
				(font
					(size 1.016 1.016)
					(thickness 0.1524)
				)
			)
		)
		(property "Device Type" "C402H22"
			(at 1.1811 -4.2291 0)
			(unlocked yes)
			(layer "F.Fab")
			(hide yes)
			(effects
				(font
					(size 1.016 1.016)
					(thickness 0.1524)
				)
			)
		)
		(duplicate_pad_numbers_are_jumpers no)
		(fp_rect
			(start -0.4318 0.9525)
			(end 0.4318 -0.9525)
			(stroke
				(width 0)
				(type default)
			)
			(fill no)
			(layer "F.CrtYd")
		)
		(fp_rect
			(start -0.4318 0.9525)
			(end 0.4318 -0.9525)
			(stroke
				(width 0)
				(type default)
			)
			(fill no)
			(layer "F.Fab")
		)
		(pad "1" smd custom
			(at 0 -0.4445)
			(size 0.1524 0.1524)
			(layers "F.Cu" "F.Mask" "F.Paste")
			(net "NIC0_CT_POWER")
			(options
				(clearance outline)
				(anchor circle)
			)
			(primitives
				(gr_poly
					(pts
						(arc
							(start 0.3048 -0.2032)
							(mid 0.275042 -0.275042)
							(end 0.2032 -0.3048)
						)
						(arc
							(start -0.2032 -0.3048)
							(mid -0.275042 -0.275042)
							(end -0.3048 -0.2032)
						)
						(arc
							(start -0.3048 0.2032)
							(mid -0.275042 0.275042)
							(end -0.2032 0.3048)
						)
						(arc
							(start 0.2032 0.3048)
							(mid 0.275042 0.275042)
							(end 0.3048 0.2032)
						)
					)
					(width 0)
					(fill yes)
				)
			)
		)
		(pad "2" smd custom
			(at 0 0.4445)
			(size 0.1524 0.1524)
			(layers "F.Cu" "F.Mask" "F.Paste")
			(net "GND")
			(options
				(clearance outline)
				(anchor circle)
			)
			(primitives
				(gr_poly
					(pts
						(arc
							(start 0.3048 -0.2032)
							(mid 0.275042 -0.275042)
							(end 0.2032 -0.3048)
						)
						(arc
							(start -0.2032 -0.3048)
							(mid -0.275042 -0.275042)
							(end -0.3048 -0.2032)
						)
						(arc
							(start -0.3048 0.2032)
							(mid -0.275042 0.275042)
							(end -0.2032 0.3048)
						)
						(arc
							(start 0.2032 0.3048)
							(mid 0.275042 0.275042)
							(end 0.3048 0.2032)
						)
					)
					(width 0)
					(fill yes)
				)
			)
		)
	)
	(footprint ""
		(layer "F.Cu")
		(at 25.371298 -87.01405)
		(property "Reference" "R416"
			(at 0 0 0)
			(layer "F.SilkS")
			(hide yes)
			(effects
				(font
					(size 1.27 1.27)
				)
			)
		)
		(property "Value" "0R2J-2-GP"
			(at 0.064008 -3.993896 0)
			(unlocked yes)
			(layer "F.Fab")
			(hide yes)
			(effects
				(font
					(size 1.016 1.016)
					(thickness 0.1524)
				)
			)
		)
		(property "Device Type" "R402H16"
			(at 0.064008 -5.517896 0)
			(unlocked yes)
			(layer "F.Fab")
			(hide yes)
			(effects
				(font
					(size 1.016 1.016)
					(thickness 0.1524)
				)
			)
		)
		(duplicate_pad_numbers_are_jumpers no)
		(fp_line
			(start -0.508 -0.9398)
			(end -0.508 0.9398)
			(stroke
				(width 0.1524)
				(type default)
			)
			(layer "F.SilkS")
		)
		(fp_line
			(start 0.508 -0.9398)
			(end -0.508 -0.9398)
			(stroke
				(width 0.1524)
				(type default)
			)
			(layer "F.SilkS")
		)
		(fp_rect
			(start -0.508 0.9398)
			(end 0.508 -0.9398)
			(stroke
				(width 0)
				(type default)
			)
			(fill no)
			(layer "F.CrtYd")
		)
		(fp_rect
			(start -0.508 0.9398)
			(end 0.508 -0.9398)
			(stroke
				(width 0)
				(type default)
			)
			(fill no)
			(layer "F.Fab")
		)
		(pad "1" smd custom
			(at 0 -0.4445)
			(size 0.1397 0.1397)
			(layers "F.Cu" "F.Mask" "F.Paste")
			(net "BMC_PERST#_R")
			(options
				(clearance outline)
				(anchor circle)
			)
			(primitives
				(gr_poly
					(pts
						(arc
							(start -0.1778 -0.2794)
							(mid -0.249642 -0.249642)
							(end -0.2794 -0.1778)
						)
						(arc
							(start -0.2794 0.1778)
							(mid -0.249642 0.249642)
							(end -0.1778 0.2794)
						)
						(arc
							(start 0.1778 0.2794)
							(mid 0.249642 0.249642)
							(end 0.2794 0.1778)
						)
						(arc
							(start 0.2794 -0.1778)
							(mid 0.249642 -0.249642)
							(end 0.1778 -0.2794)
						)
					)
					(width 0)
					(fill yes)
				)
			)
		)
		(pad "2" smd custom
			(at 0 0.4445)
			(size 0.1397 0.1397)
			(layers "F.Cu" "F.Mask" "F.Paste")
			(net "PHY_RESET_N")
			(options
				(clearance outline)
				(anchor circle)
			)
			(primitives
				(gr_poly
					(pts
						(arc
							(start -0.1778 -0.2794)
							(mid -0.249642 -0.249642)
							(end -0.2794 -0.1778)
						)
						(arc
							(start -0.2794 0.1778)
							(mid -0.249642 0.249642)
							(end -0.1778 0.2794)
						)
						(arc
							(start 0.1778 0.2794)
							(mid 0.249642 0.249642)
							(end 0.2794 0.1778)
						)
						(arc
							(start 0.2794 -0.1778)
							(mid 0.249642 -0.249642)
							(end 0.1778 -0.2794)
						)
					)
					(width 0)
					(fill yes)
				)
			)
		)
	)
	(footprint ""
		(layer "F.Cu")
		(at 341.376 -62.611 -90)
		(property "Reference" "PC172"
			(at 0 0 270)
			(layer "F.SilkS")
			(hide yes)
			(effects
				(font
					(size 1.27 1.27)
				)
			)
		)
		(property "Value" "SCD1U50V3KX-GP"
			(at 0 -2.8194 270)
			(unlocked yes)
			(layer "F.Fab")
			(hide yes)
			(effects
				(font
					(size 1.016 1.016)
					(thickness 0.1524)
				)
			)
		)
		(property "Device Type" "C603H36"
			(at 0 -4.3434 270)
			(unlocked yes)
			(layer "F.Fab")
			(hide yes)
			(effects
				(font
					(size 1.016 1.016)
					(thickness 0.1524)
				)
			)
		)
		(duplicate_pad_numbers_are_jumpers no)
		(fp_line
			(start 0.508 0)
			(end -0.508 0)
			(stroke
				(width 0.2032)
				(type default)
			)
			(layer "F.SilkS")
		)
		(fp_rect
			(start -0.5842 1.3335)
			(end 0.5842 -1.3335)
			(stroke
				(width 0)
				(type default)
			)
			(fill no)
			(layer "F.CrtYd")
		)
		(fp_rect
			(start -0.5842 1.3335)
			(end 0.5842 -1.3335)
			(stroke
				(width 0)
				(type default)
			)
			(fill no)
			(layer "F.Fab")
		)
		(pad "1" smd custom
			(at 0 -0.762 270)
			(size 0.2159 0.2159)
			(layers "F.Cu" "F.Mask" "F.Paste")
			(net "P0V9_E_VIN")
			(options
				(clearance outline)
				(anchor circle)
			)
			(primitives
				(gr_poly
					(pts
						(arc
							(start -0.3302 -0.4318)
							(mid -0.402042 -0.402042)
							(end -0.4318 -0.3302)
						)
						(arc
							(start -0.4318 0.3302)
							(mid -0.402042 0.402042)
							(end -0.3302 0.4318)
						)
						(arc
							(start 0.3302 0.4318)
							(mid 0.402042 0.402042)
							(end 0.4318 0.3302)
						)
						(arc
							(start 0.4318 -0.3302)
							(mid 0.402042 -0.402042)
							(end 0.3302 -0.4318)
						)
					)
					(width 0)
					(fill yes)
				)
			)
		)
		(pad "2" smd custom
			(at 0 0.762 270)
			(size 0.2159 0.2159)
			(layers "F.Cu" "F.Mask" "F.Paste")
			(net "GND")
			(options
				(clearance outline)
				(anchor circle)
			)
			(primitives
				(gr_poly
					(pts
						(arc
							(start -0.3302 -0.4318)
							(mid -0.402042 -0.402042)
							(end -0.4318 -0.3302)
						)
						(arc
							(start -0.4318 0.3302)
							(mid -0.402042 0.402042)
							(end -0.3302 0.4318)
						)
						(arc
							(start 0.3302 0.4318)
							(mid 0.402042 0.402042)
							(end 0.4318 0.3302)
						)
						(arc
							(start 0.4318 -0.3302)
							(mid 0.402042 -0.402042)
							(end 0.3302 -0.4318)
						)
					)
					(width 0)
					(fill yes)
				)
			)
		)
	)
	(footprint ""
		(layer "F.Cu")
		(at 43.6118 -183.2356 180)
		(property "Reference" "R867"
			(at 0 0 180)
			(layer "F.SilkS")
			(hide yes)
			(effects
				(font
					(size 1.27 1.27)
				)
			)
		)
		(property "Value" "0R2J-2-GP"
			(at 0.064008 -3.993896 180)
			(unlocked yes)
			(layer "F.Fab")
			(hide yes)
			(effects
				(font
					(size 1.016 1.016)
					(thickness 0.1524)
				)
			)
		)
		(property "Device Type" "R402H16"
			(at 0.064008 -5.517896 180)
			(unlocked yes)
			(layer "F.Fab")
			(hide yes)
			(effects
				(font
					(size 1.016 1.016)
					(thickness 0.1524)
				)
			)
		)
		(duplicate_pad_numbers_are_jumpers no)
		(fp_line
			(start 0.508 -0.9398)
			(end -0.508 -0.9398)
			(stroke
				(width 0.1524)
				(type default)
			)
			(layer "F.SilkS")
		)
		(fp_line
			(start -0.508 -0.9398)
			(end -0.508 0.9398)
			(stroke
				(width 0.1524)
				(type default)
			)
			(layer "F.SilkS")
		)
		(fp_rect
			(start -0.508 0.9398)
			(end 0.508 -0.9398)
			(stroke
				(width 0)
				(type default)
			)
			(fill no)
			(layer "F.CrtYd")
		)
		(fp_rect
			(start -0.508 0.9398)
			(end 0.508 -0.9398)
			(stroke
				(width 0)
				(type default)
			)
			(fill no)
			(layer "F.Fab")
		)
		(pad "1" smd custom
			(at 0 -0.4445 180)
			(size 0.1397 0.1397)
			(layers "F.Cu" "F.Mask" "F.Paste")
			(net "BMC_I2C9_CLKBUF2_SCL")
			(options
				(clearance outline)
				(anchor circle)
			)
			(primitives
				(gr_poly
					(pts
						(arc
							(start -0.1778 -0.2794)
							(mid -0.249642 -0.249642)
							(end -0.2794 -0.1778)
						)
						(arc
							(start -0.2794 0.1778)
							(mid -0.249642 0.249642)
							(end -0.1778 0.2794)
						)
						(arc
							(start 0.1778 0.2794)
							(mid 0.249642 0.249642)
							(end 0.2794 0.1778)
						)
						(arc
							(start 0.2794 -0.1778)
							(mid 0.249642 -0.249642)
							(end 0.1778 -0.2794)
						)
					)
					(width 0)
					(fill yes)
				)
			)
		)
		(pad "2" smd custom
			(at 0 0.4445 180)
			(size 0.1397 0.1397)
			(layers "F.Cu" "F.Mask" "F.Paste")
			(net "BMC_I2C9_CLKBUF2_SCL_R")
			(options
				(clearance outline)
				(anchor circle)
			)
			(primitives
				(gr_poly
					(pts
						(arc
							(start -0.1778 -0.2794)
							(mid -0.249642 -0.249642)
							(end -0.2794 -0.1778)
						)
						(arc
							(start -0.2794 0.1778)
							(mid -0.249642 0.249642)
							(end -0.1778 0.2794)
						)
						(arc
							(start 0.1778 0.2794)
							(mid 0.249642 0.249642)
							(end 0.2794 0.1778)
						)
						(arc
							(start 0.2794 -0.1778)
							(mid 0.249642 -0.249642)
							(end 0.1778 -0.2794)
						)
					)
					(width 0)
					(fill yes)
				)
			)
		)
	)
	(footprint ""
		(layer "F.Cu")
		(at 231.394 -23.241)
		(property "Reference" "R820"
			(at 0 0 0)
			(layer "F.SilkS")
			(hide yes)
			(effects
				(font
					(size 1.27 1.27)
				)
			)
		)
		(property "Value" "4K7R2F-GP"
			(at 0.064008 -3.993896 0)
			(unlocked yes)
			(layer "F.Fab")
			(hide yes)
			(effects
				(font
					(size 1.016 1.016)
					(thickness 0.1524)
				)
			)
		)
		(property "Device Type" "R402H16"
			(at 0.064008 -5.517896 0)
			(unlocked yes)
			(layer "F.Fab")
			(hide yes)
			(effects
				(font
					(size 1.016 1.016)
					(thickness 0.1524)
				)
			)
		)
		(duplicate_pad_numbers_are_jumpers no)
		(fp_line
			(start -0.508 -0.9398)
			(end -0.508 0.9398)
			(stroke
				(width 0.1524)
				(type default)
			)
			(layer "F.SilkS")
		)
		(fp_line
			(start 0.508 -0.9398)
			(end -0.508 -0.9398)
			(stroke
				(width 0.1524)
				(type default)
			)
			(layer "F.SilkS")
		)
		(fp_rect
			(start -0.508 0.9398)
			(end 0.508 -0.9398)
			(stroke
				(width 0)
				(type default)
			)
			(fill no)
			(layer "F.CrtYd")
		)
		(fp_rect
			(start -0.508 0.9398)
			(end 0.508 -0.9398)
			(stroke
				(width 0)
				(type default)
			)
			(fill no)
			(layer "F.Fab")
		)
		(pad "1" smd custom
			(at 0 -0.4445)
			(size 0.1397 0.1397)
			(layers "F.Cu" "F.Mask" "F.Paste")
			(net "GND")
			(options
				(clearance outline)
				(anchor circle)
			)
			(primitives
				(gr_poly
					(pts
						(arc
							(start -0.1778 -0.2794)
							(mid -0.249642 -0.249642)
							(end -0.2794 -0.1778)
						)
						(arc
							(start -0.2794 0.1778)
							(mid -0.249642 0.249642)
							(end -0.1778 0.2794)
						)
						(arc
							(start 0.1778 0.2794)
							(mid 0.249642 0.249642)
							(end 0.2794 0.1778)
						)
						(arc
							(start 0.2794 -0.1778)
							(mid 0.249642 -0.249642)
							(end 0.1778 -0.2794)
						)
					)
					(width 0)
					(fill yes)
				)
			)
		)
		(pad "2" smd custom
			(at 0 0.4445)
			(size 0.1397 0.1397)
			(layers "F.Cu" "F.Mask" "F.Paste")
			(net "BOOTSTRAP10")
			(options
				(clearance outline)
				(anchor circle)
			)
			(primitives
				(gr_poly
					(pts
						(arc
							(start -0.1778 -0.2794)
							(mid -0.249642 -0.249642)
							(end -0.2794 -0.1778)
						)
						(arc
							(start -0.2794 0.1778)
							(mid -0.249642 0.249642)
							(end -0.1778 0.2794)
						)
						(arc
							(start 0.1778 0.2794)
							(mid 0.249642 0.249642)
							(end 0.2794 0.1778)
						)
						(arc
							(start 0.2794 -0.1778)
							(mid 0.249642 -0.249642)
							(end 0.1778 -0.2794)
						)
					)
					(width 0)
					(fill yes)
				)
			)
		)
	)
)
